(kicad_pcb
	(version 20260206)
	(generator "pcbnew")
	(generator_version "10.0")
	(general
		(thickness 1.6)
		(legacy_teardrops no)
	)
	(paper "A4")
	(title_block
		(title "01162023_DA0F0TEBIF0_F0T_Expander_BD_F_brd_V02_OCP.brd")
		(comment 1 "Grand Teton / footprints 7188-7193 of 9728")
	)
	(layers
		(0 "F.Cu" signal "TOP")
		(4 "In1.Cu" signal "GND")
		(6 "In2.Cu" signal "VCC")
		(8 "In3.Cu" signal "VCC1")
		(10 "In4.Cu" signal "GND1")
		(12 "In5.Cu" signal "IN1")
		(14 "In6.Cu" signal "GND2")
		(16 "In7.Cu" signal "IN2")
		(18 "In8.Cu" signal "GND3")
		(20 "In9.Cu" signal "IN3")
		(22 "In10.Cu" signal "GND4")
		(24 "In11.Cu" signal "IN4")
		(26 "In12.Cu" signal "GND5")
		(28 "In13.Cu" signal "IN5")
		(30 "In14.Cu" signal "GND6")
		(32 "In15.Cu" signal "IN6")
		(34 "In16.Cu" signal "GND7")
		(2 "B.Cu" signal "BOTTOM")
		(9 "F.Adhes" user "F.Adhesive")
		(11 "B.Adhes" user "B.Adhesive")
		(13 "F.Paste" user "Package Geometry/Pastemask Top")
		(15 "B.Paste" user "Package Geometry/Pastemask Bottom")
		(5 "F.SilkS" user "Ref Des/Silkscreen Top")
		(7 "B.SilkS" user "Ref Des/Silkscreen Bottom")
		(1 "F.Mask" user "Board Geometry/Soldermask Top")
		(3 "B.Mask" user "Board Geometry/Soldermask Bottom")
		(17 "Dwgs.User" user "User.Drawings")
		(19 "Cmts.User" user "User.Comments")
		(21 "Eco1.User" user "User.Eco1")
		(23 "Eco2.User" user "User.Eco2")
		(25 "Edge.Cuts" user "Board Geometry/Outline")
		(27 "Margin" user)
		(31 "F.CrtYd" user "Package Geometry/Place Bound Top")
		(29 "B.CrtYd" user "Package Geometry/Place Bound Bottom")
		(35 "F.Fab" user "Ref Des/Assembly Top")
		(33 "B.Fab" user "Ref Des/Assembly Bottom")
	)
	(footprint ""
		(layer "B.Cu")
		(at 331.30363 -217.125296)
		(property "Reference" "C2078"
			(at 0 0 0)
			(layer "B.SilkS")
			(hide yes)
			(effects
				(font
					(size 1.27 1.27)
				)
				(justify mirror)
			)
		)
		(property "Value" ""
			(at 0 0 0)
			(layer "B.Fab")
			(effects
				(font
					(size 1.27 1.27)
				)
				(justify mirror)
			)
		)
		(duplicate_pad_numbers_are_jumpers no)
		(fp_line
			(start -0.69215 -0.2921)
			(end -0.69215 0.2921)
			(stroke
				(width 0.1524)
				(type default)
			)
			(layer "B.SilkS")
		)
		(fp_line
			(start -0.69215 0.2921)
			(end 0.69215 0.2921)
			(stroke
				(width 0.1524)
				(type default)
			)
			(layer "B.SilkS")
		)
		(fp_line
			(start 0.69215 -0.2921)
			(end -0.69215 -0.2921)
			(stroke
				(width 0.1524)
				(type default)
			)
			(layer "B.SilkS")
		)
		(fp_line
			(start 0.69215 0.2921)
			(end 0.69215 -0.2921)
			(stroke
				(width 0.1524)
				(type default)
			)
			(layer "B.SilkS")
		)
		(fp_line
			(start -0.51435 -0.2794)
			(end -0.51435 0.2794)
			(stroke
				(width 0.1)
				(type default)
			)
			(layer "B.Fab")
		)
		(fp_line
			(start -0.51435 0.2794)
			(end 0.51435 0.2794)
			(stroke
				(width 0.1)
				(type default)
			)
			(layer "B.Fab")
		)
		(fp_line
			(start 0.51435 -0.2794)
			(end -0.51435 -0.2794)
			(stroke
				(width 0.1)
				(type default)
			)
			(layer "B.Fab")
		)
		(fp_line
			(start 0.51435 0.2794)
			(end 0.51435 -0.2794)
			(stroke
				(width 0.1)
				(type default)
			)
			(layer "B.Fab")
		)
		(pad "1" smd circle
			(at 0.40005 0 180)
			(size 0 0)
			(layers "B.Cu" "B.Mask" "B.Paste")
			(net "P3V3_FPGA_VCCIO3")
		)
		(pad "2" smd circle
			(at -0.40005 0 180)
			(size 0 0)
			(layers "B.Cu" "B.Mask" "B.Paste")
			(net "GND")
		)
		(zone
			(layer "B.Cu")
			(hatch none 0.5)
			(connect_pads
				(clearance 0)
			)
			(min_thickness 0.25)
			(keepout
				(tracks not_allowed)
				(vias allowed)
				(pads allowed)
				(copperpour not_allowed)
				(footprints allowed)
			)
			(placement
				(enabled no)
				(sheetname "")
			)
			(fill
				(thermal_gap 0.5)
				(thermal_bridge_width 0.5)
				(island_removal_mode 0)
			)
			(polygon
				(pts
					(xy 331.49413 -217.037666) (xy 331.40269 -216.9795) (xy 331.2033 -216.9795) (xy 331.11313 -217.037666)
					(xy 331.11313 -217.212926) (xy 331.2033 -217.271346) (xy 331.40269 -217.271346) (xy 331.49413 -217.21318)
				)
			)
		)
	)
	(footprint ""
		(layer "B.Cu")
		(at 183.3499 -290.199826 90)
		(property "Reference" "C1437"
			(at 0 0 90)
			(layer "B.SilkS")
			(hide yes)
			(effects
				(font
					(size 1.27 1.27)
				)
				(justify mirror)
			)
		)
		(property "Value" ""
			(at 0 0 90)
			(layer "B.Fab")
			(effects
				(font
					(size 1.27 1.27)
				)
				(justify mirror)
			)
		)
		(duplicate_pad_numbers_are_jumpers no)
		(fp_line
			(start 0.299974 -0.150114)
			(end -0.299974 -0.150114)
			(stroke
				(width 0.1)
				(type default)
			)
			(layer "B.Fab")
		)
		(fp_line
			(start -0.299974 -0.150114)
			(end -0.299974 0.150114)
			(stroke
				(width 0.1)
				(type default)
			)
			(layer "B.Fab")
		)
		(fp_line
			(start 0.299974 0.150114)
			(end 0.299974 -0.150114)
			(stroke
				(width 0.1)
				(type default)
			)
			(layer "B.Fab")
		)
		(fp_line
			(start -0.299974 0.150114)
			(end 0.299974 0.150114)
			(stroke
				(width 0.1)
				(type default)
			)
			(layer "B.Fab")
		)
		(pad "1" smd rect
			(at 0.2667 0 270)
			(size 0.3048 0.381)
			(layers "B.Cu" "B.Mask" "B.Paste")
			(net "P0V8_SERDES_VDDA_PEX1")
		)
		(pad "2" smd rect
			(at -0.2667 0 270)
			(size 0.3048 0.381)
			(layers "B.Cu" "B.Mask" "B.Paste")
			(net "GND")
		)
	)
	(footprint ""
		(layer "B.Cu")
		(at 135.818372 -227.084382 90)
		(property "Reference" "U66"
			(at -1.970278 3.25374 270)
			(unlocked yes)
			(layer "B.SilkS")
			(effects
				(font
					(size 0.7874 0.5842)
					(thickness 0.1524)
				)
				(justify mirror)
			)
		)
		(property "Value" ""
			(at 0 0 90)
			(layer "B.Fab")
			(effects
				(font
					(size 1.27 1.27)
				)
				(justify mirror)
			)
		)
		(duplicate_pad_numbers_are_jumpers no)
		(fp_line
			(start 1.8288 -2.4892)
			(end 0.5588 -2.4892)
			(stroke
				(width 0.1524)
				(type default)
			)
			(layer "B.SilkS")
		)
		(fp_line
			(start 0.5588 -2.4892)
			(end 0 -1.9304)
			(stroke
				(width 0.1524)
				(type default)
			)
			(layer "B.SilkS")
		)
		(fp_line
			(start -0.5588 -2.4892)
			(end -1.8288 -2.4892)
			(stroke
				(width 0.1524)
				(type default)
			)
			(layer "B.SilkS")
		)
		(fp_line
			(start -1.8288 -2.4892)
			(end -1.8161 2.4892)
			(stroke
				(width 0.1524)
				(type default)
			)
			(layer "B.SilkS")
		)
		(fp_line
			(start 0 -1.9304)
			(end -0.5588 -2.4892)
			(stroke
				(width 0.1524)
				(type default)
			)
			(layer "B.SilkS")
		)
		(fp_line
			(start 1.8288 2.4892)
			(end 1.8288 -2.4892)
			(stroke
				(width 0.1524)
				(type default)
			)
			(layer "B.SilkS")
		)
		(fp_line
			(start -1.8161 2.4892)
			(end 1.8288 2.4892)
			(stroke
				(width 0.1524)
				(type default)
			)
			(layer "B.SilkS")
		)
		(fp_poly
			(pts
				(xy 4.23672 -1.989328) (xy 4.23672 -2.614168) (xy 3.683 -2.286)
			)
			(stroke
				(width 0)
				(type default)
			)
			(fill yes)
			(layer "B.SilkS")
		)
		(fp_line
			(start 1.9939 -2.4892)
			(end -1.9939 -2.4892)
			(stroke
				(width 0.1)
				(type default)
			)
			(layer "B.Fab")
		)
		(fp_line
			(start -1.9939 -2.4892)
			(end -1.9939 -2.3876)
			(stroke
				(width 0.1)
				(type default)
			)
			(layer "B.Fab")
		)
		(fp_line
			(start 3.0988 -2.3876)
			(end 1.9939 -2.3876)
			(stroke
				(width 0.1)
				(type default)
			)
			(layer "B.Fab")
		)
		(fp_line
			(start 1.9939 -2.3876)
			(end 1.9939 -2.4892)
			(stroke
				(width 0.1)
				(type default)
			)
			(layer "B.Fab")
		)
		(fp_line
			(start 1.9939 -2.3876)
			(end 1.9812 -2.3876)
			(stroke
				(width 0.1)
				(type default)
			)
			(layer "B.Fab")
		)
		(fp_line
			(start -1.9939 -2.3876)
			(end -3.0988 -2.3876)
			(stroke
				(width 0.1)
				(type default)
			)
			(layer "B.Fab")
		)
		(fp_line
			(start -1.9939 -2.3876)
			(end -1.9939 2.3876)
			(stroke
				(width 0.1)
				(type default)
			)
			(layer "B.Fab")
		)
		(fp_line
			(start -3.0988 -2.3876)
			(end -3.0988 2.3876)
			(stroke
				(width 0.1)
				(type default)
			)
			(layer "B.Fab")
		)
		(fp_line
			(start -3.0988 -2.3876)
			(end -3.0988 2.3876)
			(stroke
				(width 0.1)
				(type default)
			)
			(layer "B.Fab")
		)
		(fp_line
			(start 3.0988 2.3876)
			(end 3.0988 -2.3876)
			(stroke
				(width 0.1)
				(type default)
			)
			(layer "B.Fab")
		)
		(fp_line
			(start 3.0988 2.3876)
			(end 3.0988 -2.3876)
			(stroke
				(width 0.1)
				(type default)
			)
			(layer "B.Fab")
		)
		(fp_line
			(start 1.9939 2.3876)
			(end 1.9939 -2.3876)
			(stroke
				(width 0.1)
				(type default)
			)
			(layer "B.Fab")
		)
		(fp_line
			(start 1.9939 2.3876)
			(end 3.0988 2.3876)
			(stroke
				(width 0.1)
				(type default)
			)
			(layer "B.Fab")
		)
		(fp_line
			(start -1.9939 2.3876)
			(end -1.9939 2.4892)
			(stroke
				(width 0.1)
				(type default)
			)
			(layer "B.Fab")
		)
		(fp_line
			(start -3.0988 2.3876)
			(end -1.9939 2.3876)
			(stroke
				(width 0.1)
				(type default)
			)
			(layer "B.Fab")
		)
		(fp_line
			(start 1.9939 2.4892)
			(end 1.9939 2.3876)
			(stroke
				(width 0.1)
				(type default)
			)
			(layer "B.Fab")
		)
		(fp_line
			(start -1.9939 2.4892)
			(end 1.9939 2.4892)
			(stroke
				(width 0.1)
				(type default)
			)
			(layer "B.Fab")
		)
		(fp_line
			(start -1.9939 2.4892)
			(end -2.0066 2.4892)
			(stroke
				(width 0.1)
				(type default)
			)
			(layer "B.Fab")
		)
		(fp_line
			(start -1.9939 2.5019)
			(end -1.9939 2.4892)
			(stroke
				(width 0.1)
				(type default)
			)
			(layer "B.Fab")
		)
		(fp_poly
			(pts
				(xy 4.23672 -1.989328) (xy 4.23672 -2.614168) (xy 3.683 -2.286)
			)
			(stroke
				(width 0)
				(type default)
			)
			(fill yes)
			(layer "B.Fab")
		)
		(pad "1" smd rect
			(at 2.7432 -2.2225)
			(size 0.3556 1.5494)
			(layers "B.Cu" "B.Mask" "B.Paste")
			(net "SEL_FLASH_PEX1_BUF_R")
		)
		(pad "2" smd rect
			(at 2.7432 -1.5875)
			(size 0.3556 1.5494)
			(layers "B.Cu" "B.Mask" "B.Paste")
			(net "SPI_PEX1_CS_R_N")
		)
		(pad "3" smd rect
			(at 2.7432 -0.9525)
			(size 0.3556 1.5494)
			(layers "B.Cu" "B.Mask" "B.Paste")
			(net "SPI_BIC1_CS0_LS01_R2_N")
		)
		(pad "4" smd rect
			(at 2.7432 -0.3175)
			(size 0.3556 1.5494)
			(layers "B.Cu" "B.Mask" "B.Paste")
			(net "SPI_PEX1_CS_MUX_N")
		)
		(pad "5" smd rect
			(at 2.7432 0.3175)
			(size 0.3556 1.5494)
			(layers "B.Cu" "B.Mask" "B.Paste")
			(net "SPI_PEX1_CLK_R")
		)
		(pad "6" smd rect
			(at 2.7432 0.9525)
			(size 0.3556 1.5494)
			(layers "B.Cu" "B.Mask" "B.Paste")
			(net "SPI_BIC1_CLK_LS01_R2")
		)
		(pad "7" smd rect
			(at 2.7432 1.5875)
			(size 0.3556 1.5494)
			(layers "B.Cu" "B.Mask" "B.Paste")
			(net "SPI_PEX1_CLK_MUX")
		)
		(pad "8" smd rect
			(at 2.7432 2.2225)
			(size 0.3556 1.5494)
			(layers "B.Cu" "B.Mask" "B.Paste")
			(net "GND")
		)
		(pad "9" smd rect
			(at -2.7432 2.2225)
			(size 0.3556 1.5494)
			(layers "B.Cu" "B.Mask" "B.Paste")
			(net "SPI_PEX1_SDIO0_MUX")
		)
		(pad "10" smd rect
			(at -2.7432 1.5875)
			(size 0.3556 1.5494)
			(layers "B.Cu" "B.Mask" "B.Paste")
			(net "SPI_BIC1_MOSI_LS01_R2")
		)
		(pad "11" smd rect
			(at -2.7432 0.9525)
			(size 0.3556 1.5494)
			(layers "B.Cu" "B.Mask" "B.Paste")
			(net "SPI_PEX1_SDIO0_R")
		)
		(pad "12" smd rect
			(at -2.7432 0.3175)
			(size 0.3556 1.5494)
			(layers "B.Cu" "B.Mask" "B.Paste")
			(net "SPI_PEX1_SDIO1_MUX")
		)
		(pad "13" smd rect
			(at -2.7432 -0.3175)
			(size 0.3556 1.5494)
			(layers "B.Cu" "B.Mask" "B.Paste")
			(net "SPI_BIC1_MISO_LS01_R2")
		)
		(pad "14" smd rect
			(at -2.7432 -0.9525)
			(size 0.3556 1.5494)
			(layers "B.Cu" "B.Mask" "B.Paste")
			(net "SPI_PEX1_SDIO1_R")
		)
		(pad "15" smd rect
			(at -2.7432 -1.5875)
			(size 0.3556 1.5494)
			(layers "B.Cu" "B.Mask" "B.Paste")
			(net "SPI_MUX_PEX1_EN_N")
		)
		(pad "16" smd rect
			(at -2.7432 -2.2225)
			(size 0.3556 1.5494)
			(layers "B.Cu" "B.Mask" "B.Paste")
			(net "P3V3_AUX")
		)
	)
	(footprint ""
		(layer "B.Cu")
		(at 336.296 -207.772 90)
		(property "Reference" "R4130"
			(at 0 0 90)
			(layer "B.SilkS")
			(hide yes)
			(effects
				(font
					(size 1.27 1.27)
				)
				(justify mirror)
			)
		)
		(property "Value" ""
			(at 0 0 90)
			(layer "B.Fab")
			(effects
				(font
					(size 1.27 1.27)
				)
				(justify mirror)
			)
		)
		(duplicate_pad_numbers_are_jumpers no)
		(fp_line
			(start 0.7874 -0.4064)
			(end -0.7874 -0.4064)
			(stroke
				(width 0.1524)
				(type default)
			)
			(layer "B.SilkS")
		)
		(fp_line
			(start -0.7874 -0.4064)
			(end -0.7874 0.4064)
			(stroke
				(width 0.1524)
				(type default)
			)
			(layer "B.SilkS")
		)
		(fp_line
			(start 0.7874 0.4064)
			(end 0.7874 -0.4064)
			(stroke
				(width 0.1524)
				(type default)
			)
			(layer "B.SilkS")
		)
		(fp_line
			(start -0.7874 0.4064)
			(end 0.7874 0.4064)
			(stroke
				(width 0.1524)
				(type default)
			)
			(layer "B.SilkS")
		)
		(fp_line
			(start 0.67945 -0.305054)
			(end 0.12065 -0.305054)
			(stroke
				(width 0.1)
				(type default)
			)
			(layer "B.Fab")
		)
		(fp_line
			(start 0.12065 -0.305054)
			(end 0.12065 -0.2794)
			(stroke
				(width 0.1)
				(type default)
			)
			(layer "B.Fab")
		)
		(fp_line
			(start -0.12065 -0.3048)
			(end -0.67945 -0.3048)
			(stroke
				(width 0.1)
				(type default)
			)
			(layer "B.Fab")
		)
		(fp_line
			(start -0.67945 -0.3048)
			(end -0.67945 0.3048)
			(stroke
				(width 0.1)
				(type default)
			)
			(layer "B.Fab")
		)
		(fp_line
			(start 0.12065 -0.2794)
			(end -0.12065 -0.2794)
			(stroke
				(width 0.1)
				(type default)
			)
			(layer "B.Fab")
		)
		(fp_line
			(start -0.12065 -0.2794)
			(end -0.12065 -0.3048)
			(stroke
				(width 0.1)
				(type default)
			)
			(layer "B.Fab")
		)
		(fp_line
			(start 0.12065 0.2794)
			(end 0.12065 0.3048)
			(stroke
				(width 0.1)
				(type default)
			)
			(layer "B.Fab")
		)
		(fp_line
			(start -0.120396 0.2794)
			(end 0.12065 0.2794)
			(stroke
				(width 0.1)
				(type default)
			)
			(layer "B.Fab")
		)
		(fp_line
			(start 0.67945 0.3048)
			(end 0.67945 -0.305054)
			(stroke
				(width 0.1)
				(type default)
			)
			(layer "B.Fab")
		)
		(fp_line
			(start 0.12065 0.3048)
			(end 0.67945 0.3048)
			(stroke
				(width 0.1)
				(type default)
			)
			(layer "B.Fab")
		)
		(fp_line
			(start -0.120396 0.3048)
			(end -0.120396 0.2794)
			(stroke
				(width 0.1)
				(type default)
			)
			(layer "B.Fab")
		)
		(fp_line
			(start -0.67945 0.3048)
			(end -0.120396 0.3048)
			(stroke
				(width 0.1)
				(type default)
			)
			(layer "B.Fab")
		)
		(pad "1" smd circle
			(at 0.40005 0 270)
			(size 0 0)
			(layers "B.Cu" "B.Mask" "B.Paste")
			(net "SSD11_CLK_EN_N")
		)
		(pad "2" smd circle
			(at -0.40005 0 270)
			(size 0 0)
			(layers "B.Cu" "B.Mask" "B.Paste")
			(net "SSD11_CLK_EN_R_N")
		)
	)
	(footprint ""
		(layer "B.Cu")
		(at 105.754678 -355.714046 -90)
		(property "Reference" "R6368"
			(at 0 0 90)
			(layer "B.SilkS")
			(hide yes)
			(effects
				(font
					(size 1.27 1.27)
				)
				(justify mirror)
			)
		)
		(property "Value" ""
			(at 0 0 90)
			(layer "B.Fab")
			(effects
				(font
					(size 1.27 1.27)
				)
				(justify mirror)
			)
		)
		(duplicate_pad_numbers_are_jumpers no)
		(fp_line
			(start -0.7874 0.4064)
			(end 0.7874 0.4064)
			(stroke
				(width 0.1524)
				(type default)
			)
			(layer "B.SilkS")
		)
		(fp_line
			(start 0.7874 0.4064)
			(end 0.7874 -0.4064)
			(stroke
				(width 0.1524)
				(type default)
			)
			(layer "B.SilkS")
		)
		(fp_line
			(start -0.7874 -0.4064)
			(end -0.7874 0.4064)
			(stroke
				(width 0.1524)
				(type default)
			)
			(layer "B.SilkS")
		)
		(fp_line
			(start 0.7874 -0.4064)
			(end -0.7874 -0.4064)
			(stroke
				(width 0.1524)
				(type default)
			)
			(layer "B.SilkS")
		)
		(fp_line
			(start -0.67945 0.3048)
			(end -0.120396 0.3048)
			(stroke
				(width 0.1)
				(type default)
			)
			(layer "B.Fab")
		)
		(fp_line
			(start -0.120396 0.3048)
			(end -0.120396 0.2794)
			(stroke
				(width 0.1)
				(type default)
			)
			(layer "B.Fab")
		)
		(fp_line
			(start 0.12065 0.3048)
			(end 0.67945 0.3048)
			(stroke
				(width 0.1)
				(type default)
			)
			(layer "B.Fab")
		)
		(fp_line
			(start 0.67945 0.3048)
			(end 0.67945 -0.305054)
			(stroke
				(width 0.1)
				(type default)
			)
			(layer "B.Fab")
		)
		(fp_line
			(start -0.120396 0.2794)
			(end 0.12065 0.2794)
			(stroke
				(width 0.1)
				(type default)
			)
			(layer "B.Fab")
		)
		(fp_line
			(start 0.12065 0.2794)
			(end 0.12065 0.3048)
			(stroke
				(width 0.1)
				(type default)
			)
			(layer "B.Fab")
		)
		(fp_line
			(start -0.12065 -0.2794)
			(end -0.12065 -0.3048)
			(stroke
				(width 0.1)
				(type default)
			)
			(layer "B.Fab")
		)
		(fp_line
			(start 0.12065 -0.2794)
			(end -0.12065 -0.2794)
			(stroke
				(width 0.1)
				(type default)
			)
			(layer "B.Fab")
		)
		(fp_line
			(start -0.67945 -0.3048)
			(end -0.67945 0.3048)
			(stroke
				(width 0.1)
				(type default)
			)
			(layer "B.Fab")
		)
		(fp_line
			(start -0.12065 -0.3048)
			(end -0.67945 -0.3048)
			(stroke
				(width 0.1)
				(type default)
			)
			(layer "B.Fab")
		)
		(fp_line
			(start 0.12065 -0.305054)
			(end 0.12065 -0.2794)
			(stroke
				(width 0.1)
				(type default)
			)
			(layer "B.Fab")
		)
		(fp_line
			(start 0.67945 -0.305054)
			(end 0.12065 -0.305054)
			(stroke
				(width 0.1)
				(type default)
			)
			(layer "B.Fab")
		)
		(pad "1" smd circle
			(at 0.40005 0 90)
			(size 0 0)
			(layers "B.Cu" "B.Mask" "B.Paste")
			(net "PEX_S3_REF_CLK_BUFFER_EN_N")
		)
		(pad "2" smd circle
			(at -0.40005 0 90)
			(size 0 0)
			(layers "B.Cu" "B.Mask" "B.Paste")
			(net "P3V3")
		)
	)
	(footprint ""
		(layer "B.Cu")
		(at 53.949854 -288.299906 90)
		(property "Reference" "C2934"
			(at 0 0 90)
			(layer "B.SilkS")
			(hide yes)
			(effects
				(font
					(size 1.27 1.27)
				)
				(justify mirror)
			)
		)
		(property "Value" ""
			(at 0 0 90)
			(layer "B.Fab")
			(effects
				(font
					(size 1.27 1.27)
				)
				(justify mirror)
			)
		)
		(duplicate_pad_numbers_are_jumpers no)
		(fp_line
			(start 0.299974 -0.150114)
			(end -0.299974 -0.150114)
			(stroke
				(width 0.1)
				(type default)
			)
			(layer "B.Fab")
		)
		(fp_line
			(start -0.299974 -0.150114)
			(end -0.299974 0.150114)
			(stroke
				(width 0.1)
				(type default)
			)
			(layer "B.Fab")
		)
		(fp_line
			(start 0.299974 0.150114)
			(end 0.299974 -0.150114)
			(stroke
				(width 0.1)
				(type default)
			)
			(layer "B.Fab")
		)
		(fp_line
			(start -0.299974 0.150114)
			(end 0.299974 0.150114)
			(stroke
				(width 0.1)
				(type default)
			)
			(layer "B.Fab")
		)
		(pad "1" smd rect
			(at 0.2667 0 270)
			(size 0.3048 0.381)
			(layers "B.Cu" "B.Mask" "B.Paste")
			(net "P1V25_PEX0")
		)
		(pad "2" smd rect
			(at -0.2667 0 270)
			(size 0.3048 0.381)
			(layers "B.Cu" "B.Mask" "B.Paste")
			(net "GND")
		)
	)
)
